(kicad_pcb
	(version 20260206)
	(generator "pcbnew")
	(generator_version "10.0")
	(general
		(thickness 1.6)
		(legacy_teardrops no)
	)
	(paper "A4")
	(title_block
		(title "timecard-production-celestica-r4006 — R4006-B0001-02_R01.brd")
		(comment 1 "Time Appliance Project (Time Card) / footprints 269-272 of 1113")
	)
	(layers
		(0 "F.Cu" signal "TOP")
		(4 "In1.Cu" signal "L02_GND1")
		(6 "In2.Cu" signal "L03_SIG1")
		(8 "In3.Cu" signal "L04_GND2")
		(10 "In4.Cu" signal "L05_VCC1")
		(12 "In5.Cu" signal "L06_VCC2")
		(14 "In6.Cu" signal "L07_GND3")
		(16 "In7.Cu" signal "L08_SIG2")
		(18 "In8.Cu" signal "L09_GND4")
		(2 "B.Cu" signal "BOTTOM")
		(9 "F.Adhes" user "F.Adhesive")
		(11 "B.Adhes" user "B.Adhesive")
		(13 "F.Paste" user "Package Geometry/Pastemask Top")
		(15 "B.Paste" user "Package Geometry/Pastemask Bottom")
		(5 "F.SilkS" user "Ref Des/Silkscreen Top")
		(7 "B.SilkS" user "Ref Des/Silkscreen Bottom")
		(1 "F.Mask" user "Board Geometry/Soldermask Top")
		(3 "B.Mask" user "Board Geometry/Soldermask Bottom")
		(17 "Dwgs.User" user "User.Drawings")
		(19 "Cmts.User" user "User.Comments")
		(21 "Eco1.User" user "User.Eco1")
		(23 "Eco2.User" user "User.Eco2")
		(25 "Edge.Cuts" user "Board Geometry/Outline")
		(27 "Margin" user)
		(31 "F.CrtYd" user "Package Geometry/Place Bound Top")
		(29 "B.CrtYd" user "Package Geometry/Place Bound Bottom")
		(35 "F.Fab" user "Ref Des/Assembly Top")
		(33 "B.Fab" user "Ref Des/Assembly Bottom")
	)
	(footprint ""
		(layer "F.Cu")
		(at 129.7432 -68.7578 180)
		(property "Reference" "U21"
			(at -0.3048 2.70383 0)
			(unlocked yes)
			(layer "F.SilkS")
			(effects
				(font
					(size 0.7874 0.5842)
					(thickness 0.1524)
				)
			)
		)
		(property "Value" ""
			(at 0 0 180)
			(layer "F.Fab")
			(effects
				(font
					(size 1.27 1.27)
				)
			)
		)
		(property "Device Type" "ISL80101IRAJZ_DFN10-G222-10136A"
			(at 0.276606 2.583688 180)
			(unlocked yes)
			(layer "F.Fab")
			(hide yes)
			(effects
				(font
					(size 0.7874 0.5842)
					(thickness 0.1524)
				)
			)
		)
		(property "User Part Number" "PARTNUM*"
			(at 0.276606 3.517646 180)
			(unlocked yes)
			(layer "Cmts.User")
			(hide yes)
			(effects
				(font
					(size 0.7874 0.5842)
					(thickness 0.1524)
				)
			)
		)
		(duplicate_pad_numbers_are_jumpers no)
		(fp_line
			(start 2.290318 1.779016)
			(end -2.290318 1.779016)
			(stroke
				(width 0.1)
				(type default)
			)
			(layer "F.SilkS")
		)
		(fp_line
			(start 2.290318 -1.779016)
			(end 2.290318 1.779016)
			(stroke
				(width 0.1)
				(type default)
			)
			(layer "F.SilkS")
		)
		(fp_line
			(start -2.290318 1.779016)
			(end -2.290318 -1.779016)
			(stroke
				(width 0.1)
				(type default)
			)
			(layer "F.SilkS")
		)
		(fp_line
			(start -2.290318 -1.779016)
			(end 2.290318 -1.779016)
			(stroke
				(width 0.1)
				(type default)
			)
			(layer "F.SilkS")
		)
		(fp_poly
			(pts
				(arc
					(start -3.315462 -1.023112)
					(mid -2.553462 -1.023112)
					(end -3.315462 -1.023112)
				)
			)
			(stroke
				(width 0)
				(type default)
			)
			(fill yes)
			(layer "F.SilkS")
		)
		(fp_poly
			(pts
				(xy -0.7239 -0.1016)
				(arc
					(start -0.7239 -0.6477)
					(mid -0.290295 -0.468095)
					(end -0.4699 -0.9017)
				)
				(xy 0.7239 -0.9017) (xy 0.7239 -0.1016)
			)
			(stroke
				(width 0)
				(type default)
			)
			(fill yes)
			(layer "F.Paste")
		)
		(fp_poly
			(pts
				(arc
					(start 0.2159 0.6477)
					(mid 0.288508 0.8255)
					(end 0.46482 0.9017)
				)
				(xy -0.7239 0.9017) (xy -0.7239 0.1016) (xy 0.7239 0.1016)
				(arc
					(start 0.7239 0.64262)
					(mid 0.647736 0.466272)
					(end 0.4699 0.3937)
				)
				(arc
					(start 0.4699 0.3937)
					(mid 0.290295 0.468095)
					(end 0.2159 0.6477)
				)
			)
			(stroke
				(width 0)
				(type default)
			)
			(fill yes)
			(layer "F.Paste")
		)
		(fp_poly
			(pts
				(xy -2.544318 2.033016) (xy 2.544318 2.033016) (xy 2.544318 -2.033016) (xy -2.544318 -2.033016)
			)
			(stroke
				(width 0)
				(type default)
			)
			(fill no)
			(layer "F.CrtYd")
		)
		(fp_line
			(start 1.525016 1.525016)
			(end -1.525016 1.525016)
			(stroke
				(width 0.1)
				(type default)
			)
			(layer "F.Fab")
		)
		(fp_line
			(start 1.525016 -1.525016)
			(end 1.525016 1.525016)
			(stroke
				(width 0.1)
				(type default)
			)
			(layer "F.Fab")
		)
		(fp_line
			(start -1.525016 1.525016)
			(end -1.525016 -1.525016)
			(stroke
				(width 0.1)
				(type default)
			)
			(layer "F.Fab")
		)
		(fp_line
			(start -1.525016 -1.525016)
			(end 1.525016 -1.525016)
			(stroke
				(width 0.1)
				(type default)
			)
			(layer "F.Fab")
		)
		(fp_poly
			(pts
				(arc
					(start -3.315462 -1.023112)
					(mid -2.553462 -1.023112)
					(end -3.315462 -1.023112)
				)
			)
			(stroke
				(width 0)
				(type default)
			)
			(fill yes)
			(layer "F.Fab")
		)
		(fp_text user "6"
			(at 2.7432 0.98425 0)
			(unlocked yes)
			(layer "F.SilkS")
			(effects
				(font
					(size 0.635 0.4064)
					(thickness 0.1524)
				)
			)
		)
		(fp_text user "10"
			(at 2.71145 -0.9398 90)
			(unlocked yes)
			(layer "F.SilkS")
			(effects
				(font
					(size 0.635 0.4064)
					(thickness 0.1524)
				)
			)
		)
		(fp_text user "5"
			(at -2.8448 0.60325 0)
			(unlocked yes)
			(layer "F.SilkS")
			(effects
				(font
					(size 0.635 0.4064)
					(thickness 0.1524)
				)
			)
		)
		(fp_text user "6"
			(at 2.6162 1.05283 0)
			(unlocked yes)
			(layer "F.Fab")
			(effects
				(font
					(size 0.7874 0.5842)
					(thickness 0.1524)
				)
			)
		)
		(fp_text user "10"
			(at 2.57683 -1.3208 90)
			(unlocked yes)
			(layer "F.Fab")
			(effects
				(font
					(size 0.7874 0.5842)
					(thickness 0.1524)
				)
			)
		)
		(fp_text user "5"
			(at -2.825496 1.29921 0)
			(unlocked yes)
			(layer "F.Fab")
			(effects
				(font
					(size 0.7874 0.5842)
					(thickness 0.1524)
				)
			)
		)
		(pad "1" smd circle
			(at -1.515618 -1.000252)
			(size 0 0)
			(layers "F.Cu" "F.Mask" "F.Paste")
			(net "XP1R8V_FPGA")
		)
		(pad "2" smd rect
			(at -1.515618 -0.500126 180)
			(size 1.0414 0.3048)
			(layers "F.Cu" "F.Mask" "F.Paste")
			(net "XP1R8V_FPGA")
		)
		(pad "3" smd rect
			(at -1.515618 0 180)
			(size 1.0414 0.3048)
			(layers "F.Cu" "F.Mask" "F.Paste")
			(net "XP1R8V_FB")
		)
		(pad "4" smd rect
			(at -1.515618 0.500126 180)
			(size 1.0414 0.3048)
			(layers "F.Cu" "F.Mask" "F.Paste")
			(net "XP1R8V_PG_R")
		)
		(pad "5" smd circle
			(at -1.515618 1.000252 180)
			(size 0 0)
			(layers "F.Cu" "F.Mask" "F.Paste")
			(net "SG")
		)
		(pad "6" smd circle
			(at 1.515618 1.000252 180)
			(size 0 0)
			(layers "F.Cu" "F.Mask" "F.Paste")
			(net "XP1R8V_SS")
		)
		(pad "7" smd rect
			(at 1.515618 0.500126 180)
			(size 1.0414 0.3048)
			(layers "F.Cu" "F.Mask" "F.Paste")
			(net "XP1R8V_EN_R")
		)
		(pad "8" smd rect
			(at 1.515618 0 180)
			(size 1.0414 0.3048)
			(layers "F.Cu" "F.Mask" "F.Paste")
			(net "Net_765")
		)
		(pad "9" smd rect
			(at 1.515618 -0.500126 180)
			(size 1.0414 0.3048)
			(layers "F.Cu" "F.Mask" "F.Paste")
			(net "XP1R8V_VIN")
		)
		(pad "10" smd circle
			(at 1.515618 -1.000252)
			(size 0 0)
			(layers "F.Cu" "F.Mask" "F.Paste")
			(net "XP1R8V_VIN")
		)
		(pad "11" smd rect
			(at 0 0 180)
			(size 1.4478 1.8034)
			(layers "F.Cu" "F.Mask" "F.Paste")
			(net "SG")
		)
	)
	(footprint ""
		(layer "F.Cu")
		(at 98.806 -24.638)
		(property "Reference" "C249"
			(at -11.43 0.16637 0)
			(unlocked yes)
			(layer "F.SilkS")
			(effects
				(font
					(size 0.7874 0.5842)
					(thickness 0.1524)
				)
			)
		)
		(property "Value" "VAL*"
			(at 0.0762 2.067306 0)
			(unlocked yes)
			(layer "F.Fab")
			(hide yes)
			(effects
				(font
					(size 0.7874 0.5842)
					(thickness 0.1524)
				)
			)
		)
		(property "Tolerance" "TOL*"
			(at 0.0762 3.032506 0)
			(unlocked yes)
			(layer "Cmts.User")
			(hide yes)
			(effects
				(font
					(size 0.7874 0.5842)
					(thickness 0.1524)
				)
			)
		)
		(property "User Part Number" "PARTNUM*"
			(at 0.1016 4.023106 0)
			(unlocked yes)
			(layer "Cmts.User")
			(hide yes)
			(effects
				(font
					(size 0.7874 0.5842)
					(thickness 0.1524)
				)
			)
		)
		(property "Device Type" "CAPACITOR-G105-0B104-EK,0.1UF,A"
			(at 0.0508 1.127506 0)
			(unlocked yes)
			(layer "F.Fab")
			(hide yes)
			(effects
				(font
					(size 0.7874 0.5842)
					(thickness 0.1524)
				)
			)
		)
		(duplicate_pad_numbers_are_jumpers no)
		(fp_line
			(start -1.143 -0.5588)
			(end -1.143 0.5588)
			(stroke
				(width 0.1)
				(type default)
			)
			(layer "F.SilkS")
		)
		(fp_line
			(start -1.143 0.5588)
			(end 1.143 0.5588)
			(stroke
				(width 0.1)
				(type default)
			)
			(layer "F.SilkS")
		)
		(fp_line
			(start 1.143 -0.5588)
			(end -1.143 -0.5588)
			(stroke
				(width 0.1)
				(type default)
			)
			(layer "F.SilkS")
		)
		(fp_line
			(start 1.143 0.5588)
			(end 1.143 -0.5588)
			(stroke
				(width 0.1)
				(type default)
			)
			(layer "F.SilkS")
		)
		(fp_rect
			(start -1.143 0.5588)
			(end 1.143 -0.5588)
			(stroke
				(width 0)
				(type default)
			)
			(fill no)
			(layer "F.CrtYd")
		)
		(fp_line
			(start -0.508 -0.3048)
			(end -0.508 0.3048)
			(stroke
				(width 0.1)
				(type default)
			)
			(layer "F.Fab")
		)
		(fp_line
			(start -0.508 0.3048)
			(end 0.508 0.3048)
			(stroke
				(width 0.1)
				(type default)
			)
			(layer "F.Fab")
		)
		(fp_line
			(start 0.508 -0.3048)
			(end -0.508 -0.3048)
			(stroke
				(width 0.1)
				(type default)
			)
			(layer "F.Fab")
		)
		(fp_line
			(start 0.508 0.3048)
			(end 0.508 -0.3048)
			(stroke
				(width 0.1)
				(type default)
			)
			(layer "F.Fab")
		)
		(pad "1" smd rect
			(at -0.5334 0)
			(size 0.7112 0.6096)
			(layers "F.Cu" "F.Mask" "F.Paste")
			(net "VDD3V3_OSC_125M")
		)
		(pad "2" smd rect
			(at 0.5334 0)
			(size 0.7112 0.6096)
			(layers "F.Cu" "F.Mask" "F.Paste")
			(net "SG")
		)
		(zone
			(layer "F.Cu")
			(hatch none 0.5)
			(connect_pads
				(clearance 0)
			)
			(min_thickness 0.25)
			(keepout
				(tracks allowed)
				(vias not_allowed)
				(pads allowed)
				(copperpour not_allowed)
				(footprints allowed)
			)
			(placement
				(enabled no)
				(sheetname "")
			)
			(fill
				(thermal_gap 0.5)
				(thermal_bridge_width 0.5)
				(island_removal_mode 0)
			)
			(polygon
				(pts
					(xy 98.7298 -24.3332) (xy 98.8822 -24.3332) (xy 98.8822 -24.9428) (xy 98.7298 -24.9428)
				)
			)
		)
	)
	(footprint ""
		(layer "F.Cu")
		(at 110.3122 -24.7142 180)
		(property "Reference" "R239"
			(at 0.9652 -8.62457 0)
			(unlocked yes)
			(layer "F.SilkS")
			(effects
				(font
					(size 0.7874 0.5842)
					(thickness 0.1524)
				)
			)
		)
		(property "Value" "VAL*"
			(at 0.02032 2.13233 180)
			(unlocked yes)
			(layer "F.Fab")
			(hide yes)
			(effects
				(font
					(size 0.7874 0.5842)
					(thickness 0.1524)
				)
			)
		)
		(property "Device Type" "RESISTOR-G155-11500-01,150OHM,A"
			(at 0.008382 1.210564 180)
			(unlocked yes)
			(layer "F.Fab")
			(hide yes)
			(effects
				(font
					(size 0.7874 0.5842)
					(thickness 0.1524)
				)
			)
		)
		(property "User Part Number" "PARTNUM*"
			(at 0.02032 4.024884 180)
			(unlocked yes)
			(layer "Cmts.User")
			(hide yes)
			(effects
				(font
					(size 0.7874 0.5842)
					(thickness 0.1524)
				)
			)
		)
		(property "Tolerance" "TOL*"
			(at 0.044704 3.05435 180)
			(unlocked yes)
			(layer "Cmts.User")
			(hide yes)
			(effects
				(font
					(size 0.7874 0.5842)
					(thickness 0.1524)
				)
			)
		)
		(duplicate_pad_numbers_are_jumpers no)
		(fp_line
			(start 1.143 0.5588)
			(end 1.143 -0.5588)
			(stroke
				(width 0.1)
				(type default)
			)
			(layer "F.SilkS")
		)
		(fp_line
			(start 1.143 -0.5588)
			(end -1.143 -0.5588)
			(stroke
				(width 0.1)
				(type default)
			)
			(layer "F.SilkS")
		)
		(fp_line
			(start -1.143 0.5588)
			(end 1.143 0.5588)
			(stroke
				(width 0.1)
				(type default)
			)
			(layer "F.SilkS")
		)
		(fp_line
			(start -1.143 -0.5588)
			(end -1.143 0.5588)
			(stroke
				(width 0.1)
				(type default)
			)
			(layer "F.SilkS")
		)
		(fp_rect
			(start 1.143 0.5588)
			(end -1.143 -0.5588)
			(stroke
				(width 0)
				(type default)
			)
			(fill no)
			(layer "F.CrtYd")
		)
		(fp_line
			(start 0.508 0.3048)
			(end 0.508 -0.3048)
			(stroke
				(width 0.1)
				(type default)
			)
			(layer "F.Fab")
		)
		(fp_line
			(start 0.508 -0.3048)
			(end -0.508 -0.3048)
			(stroke
				(width 0.1)
				(type default)
			)
			(layer "F.Fab")
		)
		(fp_line
			(start -0.508 0.3048)
			(end 0.508 0.3048)
			(stroke
				(width 0.1)
				(type default)
			)
			(layer "F.Fab")
		)
		(fp_line
			(start -0.508 -0.3048)
			(end -0.508 0.3048)
			(stroke
				(width 0.1)
				(type default)
			)
			(layer "F.Fab")
		)
		(pad "1" smd rect
			(at -0.5334 0 180)
			(size 0.7112 0.6096)
			(layers "F.Cu" "F.Mask" "F.Paste")
			(net "OSC_200M_CLKN")
		)
		(pad "2" smd rect
			(at 0.5334 0 180)
			(size 0.7112 0.6096)
			(layers "F.Cu" "F.Mask" "F.Paste")
			(net "SG")
		)
		(zone
			(layer "F.Cu")
			(hatch none 0.5)
			(connect_pads
				(clearance 0)
			)
			(min_thickness 0.25)
			(keepout
				(tracks allowed)
				(vias not_allowed)
				(pads allowed)
				(copperpour not_allowed)
				(footprints allowed)
			)
			(placement
				(enabled no)
				(sheetname "")
			)
			(fill
				(thermal_gap 0.5)
				(thermal_bridge_width 0.5)
				(island_removal_mode 0)
			)
			(polygon
				(pts
					(xy 110.236 -25.019) (xy 110.236 -24.4094) (xy 110.3884 -24.4094) (xy 110.3884 -25.019)
				)
			)
		)
	)
	(footprint ""
		(layer "F.Cu")
		(at 37.1094 -99.0854)
		(property "Reference" "C75"
			(at 1.6256 6.28777 0)
			(unlocked yes)
			(layer "F.SilkS")
			(effects
				(font
					(size 0.7874 0.5842)
					(thickness 0.1524)
				)
			)
		)
		(property "Value" "VAL*"
			(at 0.193548 2.13614 0)
			(unlocked yes)
			(layer "F.Fab")
			(hide yes)
			(effects
				(font
					(size 0.7874 0.5842)
					(thickness 0.1524)
				)
			)
		)
		(property "Tolerance" "TOL*"
			(at 0.216154 3.1496 0)
			(unlocked yes)
			(layer "Cmts.User")
			(hide yes)
			(effects
				(font
					(size 0.7874 0.5842)
					(thickness 0.1524)
				)
			)
		)
		(property "Device Type" "CAPACITOR-G104-0B103-EK,0.01UFA"
			(at 0.184404 1.180592 0)
			(unlocked yes)
			(layer "F.Fab")
			(hide yes)
			(effects
				(font
					(size 0.7874 0.5842)
					(thickness 0.1524)
				)
			)
		)
		(property "User Part Number" "PARTNUM*"
			(at 0.216154 4.185666 0)
			(unlocked yes)
			(layer "Cmts.User")
			(hide yes)
			(effects
				(font
					(size 0.7874 0.5842)
					(thickness 0.1524)
				)
			)
		)
		(duplicate_pad_numbers_are_jumpers no)
		(fp_line
			(start -0.671322 -0.4445)
			(end 0.671322 -0.4445)
			(stroke
				(width 0.1)
				(type default)
			)
			(layer "F.SilkS")
		)
		(fp_line
			(start -0.671322 0.4445)
			(end -0.671322 -0.4445)
			(stroke
				(width 0.1)
				(type default)
			)
			(layer "F.SilkS")
		)
		(fp_line
			(start 0.671322 -0.4445)
			(end 0.671322 0.4445)
			(stroke
				(width 0.1)
				(type default)
			)
			(layer "F.SilkS")
		)
		(fp_line
			(start 0.671322 0.4445)
			(end -0.671322 0.4445)
			(stroke
				(width 0.1)
				(type default)
			)
			(layer "F.SilkS")
		)
		(fp_rect
			(start 0.671322 -0.4445)
			(end -0.671322 0.4445)
			(stroke
				(width 0)
				(type default)
			)
			(fill no)
			(layer "F.CrtYd")
		)
		(fp_line
			(start -0.31496 -0.1651)
			(end -0.31496 0.1651)
			(stroke
				(width 0.1)
				(type default)
			)
			(layer "F.Fab")
		)
		(fp_line
			(start -0.31496 0.1651)
			(end 0.31496 0.1651)
			(stroke
				(width 0.1)
				(type default)
			)
			(layer "F.Fab")
		)
		(fp_line
			(start 0.31496 -0.1651)
			(end -0.31496 -0.1651)
			(stroke
				(width 0.1)
				(type default)
			)
			(layer "F.Fab")
		)
		(fp_line
			(start 0.31496 0.1651)
			(end 0.31496 -0.1651)
			(stroke
				(width 0.1)
				(type default)
			)
			(layer "F.Fab")
		)
		(pad "1" smd rect
			(at -0.264922 0)
			(size 0.3048 0.381)
			(layers "F.Cu" "F.Mask" "F.Paste")
			(net "SG")
		)
		(pad "2" smd rect
			(at 0.264922 0)
			(size 0.3048 0.381)
			(layers "F.Cu" "F.Mask" "F.Paste")
			(net "XP5R0V_PG")
		)
		(zone
			(layer "F.Cu")
			(hatch none 0.5)
			(connect_pads
				(clearance 0)
			)
			(min_thickness 0.25)
			(keepout
				(tracks allowed)
				(vias not_allowed)
				(pads allowed)
				(copperpour not_allowed)
				(footprints allowed)
			)
			(placement
				(enabled no)
				(sheetname "")
			)
			(fill
				(thermal_gap 0.5)
				(thermal_bridge_width 0.5)
				(island_removal_mode 0)
			)
			(polygon
				(pts
					(xy 37.221922 -99.2759) (xy 36.996878 -99.2759) (xy 36.996878 -98.8949) (xy 37.221922 -98.8949)
				)
			)
		)
	)
)
